-- pcdb file, Rev:1.0 written by Allegro Design Entry HDL 16.5-S008 (v16-5-13Y) 10/18/2011 on Tue Oct 25 14:26:29 2011
#ISCELL
  mstr_standard drawing *
  *
#ISCELL
  mstr_standard synonym *
  page1_4p
